(kicad_pcb
	(version 20260206)
	(generator "pcbnew")
	(generator_version "10.0")
	(general
		(thickness 1.6)
		(legacy_teardrops no)
	)
	(paper "A4")
	(title_block
		(title "04192023_DAF0TMB3IC0_F0TG_MB_C_brd_V02_OCP.brd")
		(comment 1 "Grand Teton / footprints 30-33 of 8354")
	)
	(layers
		(0 "F.Cu" signal "TOP")
		(4 "In1.Cu" signal "GND")
		(6 "In2.Cu" signal "IN1")
		(8 "In3.Cu" signal "GND1")
		(10 "In4.Cu" signal "IN2")
		(12 "In5.Cu" signal "GND2")
		(14 "In6.Cu" signal "IN3")
		(16 "In7.Cu" signal "GND3")
		(18 "In8.Cu" signal "VCC")
		(20 "In9.Cu" signal "VCC1")
		(22 "In10.Cu" signal "GND4")
		(24 "In11.Cu" signal "IN4")
		(26 "In12.Cu" signal "GND5")
		(28 "In13.Cu" signal "IN5")
		(30 "In14.Cu" signal "GND6")
		(32 "In15.Cu" signal "IN6")
		(34 "In16.Cu" signal "GND7")
		(2 "B.Cu" signal "BOTTOM")
		(9 "F.Adhes" user "F.Adhesive")
		(11 "B.Adhes" user "B.Adhesive")
		(13 "F.Paste" user "Package Geometry/Pastemask Top")
		(15 "B.Paste" user "Package Geometry/Pastemask Bottom")
		(5 "F.SilkS" user "Ref Des/Silkscreen Top")
		(7 "B.SilkS" user "Ref Des/Silkscreen Bottom")
		(1 "F.Mask" user "Board Geometry/Soldermask Top")
		(3 "B.Mask" user "Board Geometry/Soldermask Bottom")
		(17 "Dwgs.User" user "User.Drawings")
		(19 "Cmts.User" user "User.Comments")
		(21 "Eco1.User" user "User.Eco1")
		(23 "Eco2.User" user "User.Eco2")
		(25 "Edge.Cuts" user "Board Geometry/Outline")
		(27 "Margin" user)
		(31 "F.CrtYd" user "Package Geometry/Place Bound Top")
		(29 "B.CrtYd" user "Package Geometry/Place Bound Bottom")
		(35 "F.Fab" user "Ref Des/Assembly Top")
		(33 "B.Fab" user "Ref Des/Assembly Bottom")
	)
	(footprint ""
		(layer "F.Cu")
		(at 506.598428 -147.926806 -90)
		(property "Reference" "X9"
			(at -1.73355 3.189224 0)
			(unlocked yes)
			(layer "F.SilkS")
			(effects
				(font
					(size 0.7874 0.5842)
					(thickness 0.1524)
				)
				(justify left)
			)
		)
		(property "Value" ""
			(at 0 0 270)
			(layer "F.Fab")
			(effects
				(font
					(size 1.27 1.27)
				)
			)
		)
		(property "Device Type" "TP_TDR_4P_FTS_TH-TP_TDR_4P_DIP,EMPTY,TP15"
			(at 1.30175 1.27 0)
			(unlocked yes)
			(layer "F.Fab")
			(hide yes)
			(effects
				(font
					(size 0.635 0.4064)
					(thickness 0.1524)
				)
			)
		)
		(property "User Part Number" "N_A"
			(at 1.30175 1.27 0)
			(unlocked yes)
			(layer "Cmts.User")
			(hide yes)
			(effects
				(font
					(size 0.635 0.4064)
					(thickness 0.1524)
				)
			)
		)
		(duplicate_pad_numbers_are_jumpers no)
		(fp_line
			(start 0 3.81)
			(end 2.54 3.81)
			(stroke
				(width 0.1524)
				(type default)
			)
			(layer "F.SilkS")
		)
		(fp_line
			(start 2.54 3.81)
			(end 2.54 3.6703)
			(stroke
				(width 0.1524)
				(type default)
			)
			(layer "F.SilkS")
		)
		(fp_line
			(start 0 3.175)
			(end 0 3.81)
			(stroke
				(width 0.1524)
				(type default)
			)
			(layer "F.SilkS")
		)
		(fp_line
			(start 2.54 1.4097)
			(end 2.54 1.1303)
			(stroke
				(width 0.1524)
				(type default)
			)
			(layer "F.SilkS")
		)
		(fp_line
			(start 0 0.635)
			(end 0 1.905)
			(stroke
				(width 0.1524)
				(type default)
			)
			(layer "F.SilkS")
		)
		(fp_line
			(start 2.54 -1.1303)
			(end 2.54 -1.27)
			(stroke
				(width 0.1524)
				(type default)
			)
			(layer "F.SilkS")
		)
		(fp_line
			(start 0 -1.27)
			(end 0 -0.635)
			(stroke
				(width 0.1524)
				(type default)
			)
			(layer "F.SilkS")
		)
		(fp_line
			(start 2.54 -1.27)
			(end 0 -1.27)
			(stroke
				(width 0.1524)
				(type default)
			)
			(layer "F.SilkS")
		)
		(fp_poly
			(pts
				(xy -0.761746 0) (xy -2.285746 0.762) (xy -2.285746 -0.762)
			)
			(stroke
				(width 0)
				(type default)
			)
			(fill yes)
			(layer "F.SilkS")
		)
		(fp_line
			(start 0 3.81)
			(end 2.54 3.81)
			(stroke
				(width 0.1)
				(type default)
			)
			(layer "F.Fab")
		)
		(fp_line
			(start 2.54 3.81)
			(end 2.54 -1.27)
			(stroke
				(width 0.1)
				(type default)
			)
			(layer "F.Fab")
		)
		(fp_line
			(start 0 -1.27)
			(end 0 3.81)
			(stroke
				(width 0.1)
				(type default)
			)
			(layer "F.Fab")
		)
		(fp_line
			(start 2.54 -1.27)
			(end 0 -1.27)
			(stroke
				(width 0.1)
				(type default)
			)
			(layer "F.Fab")
		)
		(fp_poly
			(pts
				(xy -0.761746 0) (xy -2.285746 -0.762) (xy -2.285746 0.762)
			)
			(stroke
				(width 0)
				(type default)
			)
			(fill yes)
			(layer "F.Fab")
		)
		(pad "1" thru_hole circle
			(at 0 0 270)
			(size 1.0033 1.0033)
			(drill 0.249936)
			(layers "*.Cu" "*.Mask")
			(remove_unused_layers no)
			(net "TDR_DIFF_80_IN2_DN")
			(clearance 0.10795)
			(thermal_gap 0.10795)
			(padstack
				(mode front_inner_back)
				(layer "Inner"
					(shape circle)
					(size 0.8001 0.8001)
					(clearance 0.1524)
				)
				(layer "B.Cu"
					(shape circle)
					(size 1.0033 1.0033)
					(clearance 0.10795)
				)
			)
		)
		(pad "2" thru_hole circle
			(at 2.54 0 270)
			(size 1.9939 1.9939)
			(drill 0.249936)
			(layers "*.Cu" "*.Mask")
			(remove_unused_layers no)
			(net "T1_GND")
			(clearance 0.10795)
			(thermal_gap 0.10795)
			(padstack
				(mode front_inner_back)
				(layer "Inner"
					(shape circle)
					(size 0.8001 0.8001)
					(clearance 0.1524)
				)
				(layer "B.Cu"
					(shape circle)
					(size 1.9939 1.9939)
					(clearance 0.10795)
				)
			)
		)
		(pad "3" thru_hole circle
			(at 2.54 2.54 270)
			(size 1.9939 1.9939)
			(drill 0.249936)
			(layers "*.Cu" "*.Mask")
			(remove_unused_layers no)
			(net "T1_GND")
			(clearance 0.10795)
			(thermal_gap 0.10795)
			(padstack
				(mode front_inner_back)
				(layer "Inner"
					(shape circle)
					(size 0.8001 0.8001)
					(clearance 0.1524)
				)
				(layer "B.Cu"
					(shape circle)
					(size 1.9939 1.9939)
					(clearance 0.10795)
				)
			)
		)
		(pad "4" thru_hole circle
			(at 0 2.54 270)
			(size 1.0033 1.0033)
			(drill 0.249936)
			(layers "*.Cu" "*.Mask")
			(remove_unused_layers no)
			(net "TDR_DIFF_80_IN2_DP")
			(clearance 0.10795)
			(thermal_gap 0.10795)
			(padstack
				(mode front_inner_back)
				(layer "Inner"
					(shape circle)
					(size 0.8001 0.8001)
					(clearance 0.1524)
				)
				(layer "B.Cu"
					(shape circle)
					(size 1.0033 1.0033)
					(clearance 0.10795)
				)
			)
		)
	)
	(footprint ""
		(layer "F.Cu")
		(at 188.122306 -332.744572 -90)
		(property "Reference" "PC532"
			(at -4.24434 12.521692 90)
			(unlocked yes)
			(layer "F.SilkS")
			(effects
				(font
					(size 0.7874 0.5842)
					(thickness 0.1524)
				)
				(justify left)
			)
		)
		(property "Value" ""
			(at 0 0 270)
			(layer "F.Fab")
			(effects
				(font
					(size 1.27 1.27)
				)
			)
		)
		(duplicate_pad_numbers_are_jumpers no)
		(fp_line
			(start -1.988058 2.750058)
			(end 2.750058 2.750058)
			(stroke
				(width 0.1524)
				(type default)
			)
			(layer "F.SilkS")
		)
		(fp_line
			(start 2.750058 2.750058)
			(end 2.750058 0.9398)
			(stroke
				(width 0.1524)
				(type default)
			)
			(layer "F.SilkS")
		)
		(fp_line
			(start -2.750058 1.988058)
			(end -1.988058 2.750058)
			(stroke
				(width 0.1524)
				(type default)
			)
			(layer "F.SilkS")
		)
		(fp_line
			(start -2.750058 0.9398)
			(end -2.750058 1.988058)
			(stroke
				(width 0.1524)
				(type default)
			)
			(layer "F.SilkS")
		)
		(fp_line
			(start 2.750058 -0.9398)
			(end 2.750058 -2.750058)
			(stroke
				(width 0.1524)
				(type default)
			)
			(layer "F.SilkS")
		)
		(fp_line
			(start -2.750058 -1.988058)
			(end -2.750058 -0.9398)
			(stroke
				(width 0.1524)
				(type default)
			)
			(layer "F.SilkS")
		)
		(fp_line
			(start -1.988058 -2.750058)
			(end -2.750058 -1.988058)
			(stroke
				(width 0.1524)
				(type default)
			)
			(layer "F.SilkS")
		)
		(fp_line
			(start 2.750058 -2.750058)
			(end -1.988058 -2.750058)
			(stroke
				(width 0.1524)
				(type default)
			)
			(layer "F.SilkS")
		)
		(fp_line
			(start -2.750058 2.750058)
			(end 2.750058 2.750058)
			(stroke
				(width 0.1)
				(type default)
			)
			(layer "F.Fab")
		)
		(fp_line
			(start 2.750058 2.750058)
			(end 2.750058 -2.750058)
			(stroke
				(width 0.1)
				(type default)
			)
			(layer "F.Fab")
		)
		(fp_line
			(start -2.750058 -2.750058)
			(end -2.750058 2.750058)
			(stroke
				(width 0.1)
				(type default)
			)
			(layer "F.Fab")
		)
		(fp_line
			(start 2.750058 -2.750058)
			(end -2.750058 -2.750058)
			(stroke
				(width 0.1)
				(type default)
			)
			(layer "F.Fab")
		)
		(pad "1" smd rect
			(at -2.199894 0)
			(size 1.6002 3.0226)
			(layers "F.Cu" "F.Mask" "F.Paste")
			(net "PVDD11_S3_P1")
		)
		(pad "2" smd rect
			(at 2.199894 0)
			(size 1.6002 3.0226)
			(layers "F.Cu" "F.Mask" "F.Paste")
			(net "GND")
		)
	)
	(footprint ""
		(layer "F.Cu")
		(at 372.937278 -143.504158)
		(property "Reference" "R8299"
			(at 0 0 0)
			(layer "F.SilkS")
			(hide yes)
			(effects
				(font
					(size 1.27 1.27)
				)
			)
		)
		(property "Value" ""
			(at 0 0 0)
			(layer "F.Fab")
			(effects
				(font
					(size 1.27 1.27)
				)
			)
		)
		(duplicate_pad_numbers_are_jumpers no)
		(fp_line
			(start -0.7874 -0.4064)
			(end 0.7874 -0.4064)
			(stroke
				(width 0.1524)
				(type default)
			)
			(layer "F.SilkS")
		)
		(fp_line
			(start -0.7874 0.4064)
			(end -0.7874 -0.4064)
			(stroke
				(width 0.1524)
				(type default)
			)
			(layer "F.SilkS")
		)
		(fp_line
			(start 0.7874 -0.4064)
			(end 0.7874 0.4064)
			(stroke
				(width 0.1524)
				(type default)
			)
			(layer "F.SilkS")
		)
		(fp_line
			(start 0.7874 0.4064)
			(end -0.7874 0.4064)
			(stroke
				(width 0.1524)
				(type default)
			)
			(layer "F.SilkS")
		)
		(fp_line
			(start -0.67945 -0.305054)
			(end -0.12065 -0.305054)
			(stroke
				(width 0.1)
				(type default)
			)
			(layer "F.Fab")
		)
		(fp_line
			(start -0.67945 0.3048)
			(end -0.67945 -0.305054)
			(stroke
				(width 0.1)
				(type default)
			)
			(layer "F.Fab")
		)
		(fp_line
			(start -0.12065 -0.305054)
			(end -0.12065 -0.2794)
			(stroke
				(width 0.1)
				(type default)
			)
			(layer "F.Fab")
		)
		(fp_line
			(start -0.12065 -0.2794)
			(end 0.12065 -0.2794)
			(stroke
				(width 0.1)
				(type default)
			)
			(layer "F.Fab")
		)
		(fp_line
			(start -0.12065 0.2794)
			(end -0.12065 0.3048)
			(stroke
				(width 0.1)
				(type default)
			)
			(layer "F.Fab")
		)
		(fp_line
			(start -0.12065 0.3048)
			(end -0.67945 0.3048)
			(stroke
				(width 0.1)
				(type default)
			)
			(layer "F.Fab")
		)
		(fp_line
			(start 0.120396 0.2794)
			(end -0.12065 0.2794)
			(stroke
				(width 0.1)
				(type default)
			)
			(layer "F.Fab")
		)
		(fp_line
			(start 0.120396 0.3048)
			(end 0.120396 0.2794)
			(stroke
				(width 0.1)
				(type default)
			)
			(layer "F.Fab")
		)
		(fp_line
			(start 0.12065 -0.3048)
			(end 0.67945 -0.3048)
			(stroke
				(width 0.1)
				(type default)
			)
			(layer "F.Fab")
		)
		(fp_line
			(start 0.12065 -0.2794)
			(end 0.12065 -0.3048)
			(stroke
				(width 0.1)
				(type default)
			)
			(layer "F.Fab")
		)
		(fp_line
			(start 0.67945 -0.3048)
			(end 0.67945 0.3048)
			(stroke
				(width 0.1)
				(type default)
			)
			(layer "F.Fab")
		)
		(fp_line
			(start 0.67945 0.3048)
			(end 0.120396 0.3048)
			(stroke
				(width 0.1)
				(type default)
			)
			(layer "F.Fab")
		)
		(pad "1" smd circle
			(at -0.40005 0)
			(size 0 0)
			(layers "F.Cu" "F.Mask" "F.Paste")
			(net "PWRGD_PVDDCR_SOC_P0")
		)
		(pad "2" smd circle
			(at 0.40005 0)
			(size 0 0)
			(layers "F.Cu" "F.Mask" "F.Paste")
			(net "PWRGD_PVDDCR_SOC_P0_R")
		)
	)
	(footprint ""
		(layer "F.Cu")
		(at 417.018216 -332.628494 -90)
		(property "Reference" "PC222"
			(at 0 0 270)
			(layer "F.SilkS")
			(hide yes)
			(effects
				(font
					(size 1.27 1.27)
				)
			)
		)
		(property "Value" ""
			(at 0 0 270)
			(layer "F.Fab")
			(effects
				(font
					(size 1.27 1.27)
				)
			)
		)
		(duplicate_pad_numbers_are_jumpers no)
		(fp_line
			(start -0.7874 0.4064)
			(end -0.7874 -0.4064)
			(stroke
				(width 0.1524)
				(type default)
			)
			(layer "F.SilkS")
		)
		(fp_line
			(start 0.7874 0.4064)
			(end -0.7874 0.4064)
			(stroke
				(width 0.1524)
				(type default)
			)
			(layer "F.SilkS")
		)
		(fp_line
			(start -0.7874 -0.4064)
			(end 0.7874 -0.4064)
			(stroke
				(width 0.1524)
				(type default)
			)
			(layer "F.SilkS")
		)
		(fp_line
			(start 0.7874 -0.4064)
			(end 0.7874 0.4064)
			(stroke
				(width 0.1524)
				(type default)
			)
			(layer "F.SilkS")
		)
		(fp_line
			(start -0.67945 0.3048)
			(end -0.67945 -0.305054)
			(stroke
				(width 0.1)
				(type default)
			)
			(layer "F.Fab")
		)
		(fp_line
			(start -0.12065 0.3048)
			(end -0.67945 0.3048)
			(stroke
				(width 0.1)
				(type default)
			)
			(layer "F.Fab")
		)
		(fp_line
			(start 0.120396 0.3048)
			(end 0.120396 0.2794)
			(stroke
				(width 0.1)
				(type default)
			)
			(layer "F.Fab")
		)
		(fp_line
			(start 0.67945 0.3048)
			(end 0.120396 0.3048)
			(stroke
				(width 0.1)
				(type default)
			)
			(layer "F.Fab")
		)
		(fp_line
			(start -0.12065 0.2794)
			(end -0.12065 0.3048)
			(stroke
				(width 0.1)
				(type default)
			)
			(layer "F.Fab")
		)
		(fp_line
			(start 0.120396 0.2794)
			(end -0.12065 0.2794)
			(stroke
				(width 0.1)
				(type default)
			)
			(layer "F.Fab")
		)
		(fp_line
			(start -0.12065 -0.2794)
			(end 0.12065 -0.2794)
			(stroke
				(width 0.1)
				(type default)
			)
			(layer "F.Fab")
		)
		(fp_line
			(start 0.12065 -0.2794)
			(end 0.12065 -0.3048)
			(stroke
				(width 0.1)
				(type default)
			)
			(layer "F.Fab")
		)
		(fp_line
			(start 0.12065 -0.3048)
			(end 0.67945 -0.3048)
			(stroke
				(width 0.1)
				(type default)
			)
			(layer "F.Fab")
		)
		(fp_line
			(start 0.67945 -0.3048)
			(end 0.67945 0.3048)
			(stroke
				(width 0.1)
				(type default)
			)
			(layer "F.Fab")
		)
		(fp_line
			(start -0.67945 -0.305054)
			(end -0.12065 -0.305054)
			(stroke
				(width 0.1)
				(type default)
			)
			(layer "F.Fab")
		)
		(fp_line
			(start -0.12065 -0.305054)
			(end -0.12065 -0.2794)
			(stroke
				(width 0.1)
				(type default)
			)
			(layer "F.Fab")
		)
		(pad "1" smd circle
			(at -0.40005 0 270)
			(size 0 0)
			(layers "F.Cu" "F.Mask" "F.Paste")
			(net "PVDD11_S3_P0")
		)
		(pad "2" smd circle
			(at 0.40005 0 270)
			(size 0 0)
			(layers "F.Cu" "F.Mask" "F.Paste")
			(net "GND")
		)
	)
)
